# S9S_MB_2U (Grand Teton) — schematic netlist excerpt (pin names and nets, part order shuffled) for the footprints in the layout excerpt that follows; sources: Cadence DE-HDL packaged netlist, KiCad conversion of 03242023_DA0F0TMBIJ0_F0T_Motherboard_J_brd_V01_OCP.brd

R570  Q_RES  4.7K 1% CHIP  pkg 0402LF  page 206 : A = PD_DB2000_SMB_SA0 ; B = GND
C80  Q_CAP  10UF 16V 10% X6S  pkg C0805  page 111 : A = P12V_S3_AUX_CPU1_NVDIMM ; B = GND
C1886  Q_CAP  0.1UF 25V 10% X7R  pkg 0402  page 212 : A = VFG3P3_CLK_GEN ; B = GND

(kicad_pcb
	(version 20260206)
	(generator "pcbnew")
	(generator_version "10.0")
	(general
		(thickness 1.6)
		(legacy_teardrops no)
	)
	(paper "A4")
	(title_block
		(title "03242023_DA0F0TMBIJ0_F0T_Motherboard_J_brd_V01_OCP.brd")
		(comment 1 "Grand Teton / footprints 5846-5848 of 6105")
	)
	(layers
		(0 "F.Cu" signal "TOP")
		(4 "In1.Cu" signal "GND")
		(6 "In2.Cu" signal "IN1")
		(8 "In3.Cu" signal "GND1")
		(10 "In4.Cu" signal "IN2")
		(12 "In5.Cu" signal "GND2")
		(14 "In6.Cu" signal "IN3")
		(16 "In7.Cu" signal "GND3")
		(18 "In8.Cu" signal "VCC")
		(20 "In9.Cu" signal "VCC1")
		(22 "In10.Cu" signal "GND4")
		(24 "In11.Cu" signal "IN4")
		(26 "In12.Cu" signal "GND5")
		(28 "In13.Cu" signal "IN5")
		(30 "In14.Cu" signal "GND6")
		(32 "In15.Cu" signal "IN6")
		(34 "In16.Cu" signal "GND7")
		(2 "B.Cu" signal "BOTTOM")
		(9 "F.Adhes" user "F.Adhesive")
		(11 "B.Adhes" user "B.Adhesive")
		(13 "F.Paste" user "Package Geometry/Pastemask Top")
		(15 "B.Paste" user "Package Geometry/Pastemask Bottom")
		(5 "F.SilkS" user "Ref Des/Silkscreen Top")
		(7 "B.SilkS" user "Ref Des/Silkscreen Bottom")
		(1 "F.Mask" user "Board Geometry/Soldermask Top")
		(3 "B.Mask" user "Board Geometry/Soldermask Bottom")
		(17 "Dwgs.User" user "User.Drawings")
		(19 "Cmts.User" user "User.Comments")
		(21 "Eco1.User" user "User.Eco1")
		(23 "Eco2.User" user "User.Eco2")
		(25 "Edge.Cuts" user "Board Geometry/Outline")
		(27 "Margin" user)
		(31 "F.CrtYd" user "Package Geometry/Place Bound Top")
		(29 "B.CrtYd" user "Package Geometry/Place Bound Bottom")
		(35 "F.Fab" user "Ref Des/Assembly Top")
		(33 "B.Fab" user "Ref Des/Assembly Bottom")
	)
	(footprint ""
		(layer "B.Cu")
		(at 246.984266 -128.343914 -90)
		(property "Reference" "R570"
			(at 0 0 90)
			(layer "B.SilkS")
			(hide yes)
			(effects
				(font
					(size 1.27 1.27)
				)
				(justify mirror)
			)
		)
		(property "Value" ""
			(at 0 0 90)
			(layer "B.Fab")
			(effects
				(font
					(size 1.27 1.27)
				)
				(justify mirror)
			)
		)
		(duplicate_pad_numbers_are_jumpers no)
		(fp_line
			(start -0.7874 0.4064)
			(end 0.7874 0.4064)
			(stroke
				(width 0.1524)
				(type default)
			)
			(layer "B.SilkS")
		)
		(fp_line
			(start 0.7874 0.4064)
			(end 0.7874 -0.4064)
			(stroke
				(width 0.1524)
				(type default)
			)
			(layer "B.SilkS")
		)
		(fp_line
			(start -0.7874 -0.4064)
			(end -0.7874 0.4064)
			(stroke
				(width 0.1524)
				(type default)
			)
			(layer "B.SilkS")
		)
		(fp_line
			(start 0.7874 -0.4064)
			(end -0.7874 -0.4064)
			(stroke
				(width 0.1524)
				(type default)
			)
			(layer "B.SilkS")
		)
		(fp_line
			(start -0.67945 0.3048)
			(end -0.120396 0.3048)
			(stroke
				(width 0.1)
				(type default)
			)
			(layer "B.Fab")
		)
		(fp_line
			(start -0.120396 0.3048)
			(end -0.120396 0.2794)
			(stroke
				(width 0.1)
				(type default)
			)
			(layer "B.Fab")
		)
		(fp_line
			(start 0.12065 0.3048)
			(end 0.67945 0.3048)
			(stroke
				(width 0.1)
				(type default)
			)
			(layer "B.Fab")
		)
		(fp_line
			(start 0.67945 0.3048)
			(end 0.67945 -0.305054)
			(stroke
				(width 0.1)
				(type default)
			)
			(layer "B.Fab")
		)
		(fp_line
			(start -0.120396 0.2794)
			(end 0.12065 0.2794)
			(stroke
				(width 0.1)
				(type default)
			)
			(layer "B.Fab")
		)
		(fp_line
			(start 0.12065 0.2794)
			(end 0.12065 0.3048)
			(stroke
				(width 0.1)
				(type default)
			)
			(layer "B.Fab")
		)
		(fp_line
			(start -0.12065 -0.2794)
			(end -0.12065 -0.3048)
			(stroke
				(width 0.1)
				(type default)
			)
			(layer "B.Fab")
		)
		(fp_line
			(start 0.12065 -0.2794)
			(end -0.12065 -0.2794)
			(stroke
				(width 0.1)
				(type default)
			)
			(layer "B.Fab")
		)
		(fp_line
			(start -0.67945 -0.3048)
			(end -0.67945 0.3048)
			(stroke
				(width 0.1)
				(type default)
			)
			(layer "B.Fab")
		)
		(fp_line
			(start -0.12065 -0.3048)
			(end -0.67945 -0.3048)
			(stroke
				(width 0.1)
				(type default)
			)
			(layer "B.Fab")
		)
		(fp_line
			(start 0.12065 -0.305054)
			(end 0.12065 -0.2794)
			(stroke
				(width 0.1)
				(type default)
			)
			(layer "B.Fab")
		)
		(fp_line
			(start 0.67945 -0.305054)
			(end 0.12065 -0.305054)
			(stroke
				(width 0.1)
				(type default)
			)
			(layer "B.Fab")
		)
		(pad "1" smd circle
			(at 0.40005 0 90)
			(size 0 0)
			(layers "B.Cu" "B.Mask" "B.Paste")
			(net "PD_DB2000_SMB_SA0")
		)
		(pad "2" smd circle
			(at -0.40005 0 90)
			(size 0 0)
			(layers "B.Cu" "B.Mask" "B.Paste")
			(net "GND")
		)
	)
	(footprint ""
		(layer "B.Cu")
		(at 237.24108 -252.113288 90)
		(property "Reference" "C1886"
			(at 0 0 90)
			(layer "B.SilkS")
			(hide yes)
			(effects
				(font
					(size 1.27 1.27)
				)
				(justify mirror)
			)
		)
		(property "Value" ""
			(at 0 0 90)
			(layer "B.Fab")
			(effects
				(font
					(size 1.27 1.27)
				)
				(justify mirror)
			)
		)
		(duplicate_pad_numbers_are_jumpers no)
		(fp_line
			(start 0.7874 -0.4064)
			(end -0.7874 -0.4064)
			(stroke
				(width 0.1524)
				(type default)
			)
			(layer "B.SilkS")
		)
		(fp_line
			(start -0.7874 -0.4064)
			(end -0.7874 0.4064)
			(stroke
				(width 0.1524)
				(type default)
			)
			(layer "B.SilkS")
		)
		(fp_line
			(start 0.7874 0.4064)
			(end 0.7874 -0.4064)
			(stroke
				(width 0.1524)
				(type default)
			)
			(layer "B.SilkS")
		)
		(fp_line
			(start -0.7874 0.4064)
			(end 0.7874 0.4064)
			(stroke
				(width 0.1524)
				(type default)
			)
			(layer "B.SilkS")
		)
		(fp_line
			(start 0.67945 -0.305054)
			(end 0.12065 -0.305054)
			(stroke
				(width 0.1)
				(type default)
			)
			(layer "B.Fab")
		)
		(fp_line
			(start 0.12065 -0.305054)
			(end 0.12065 -0.2794)
			(stroke
				(width 0.1)
				(type default)
			)
			(layer "B.Fab")
		)
		(fp_line
			(start -0.12065 -0.3048)
			(end -0.67945 -0.3048)
			(stroke
				(width 0.1)
				(type default)
			)
			(layer "B.Fab")
		)
		(fp_line
			(start -0.67945 -0.3048)
			(end -0.67945 0.3048)
			(stroke
				(width 0.1)
				(type default)
			)
			(layer "B.Fab")
		)
		(fp_line
			(start 0.12065 -0.2794)
			(end -0.12065 -0.2794)
			(stroke
				(width 0.1)
				(type default)
			)
			(layer "B.Fab")
		)
		(fp_line
			(start -0.12065 -0.2794)
			(end -0.12065 -0.3048)
			(stroke
				(width 0.1)
				(type default)
			)
			(layer "B.Fab")
		)
		(fp_line
			(start 0.12065 0.2794)
			(end 0.12065 0.3048)
			(stroke
				(width 0.1)
				(type default)
			)
			(layer "B.Fab")
		)
		(fp_line
			(start -0.120396 0.2794)
			(end 0.12065 0.2794)
			(stroke
				(width 0.1)
				(type default)
			)
			(layer "B.Fab")
		)
		(fp_line
			(start 0.67945 0.3048)
			(end 0.67945 -0.305054)
			(stroke
				(width 0.1)
				(type default)
			)
			(layer "B.Fab")
		)
		(fp_line
			(start 0.12065 0.3048)
			(end 0.67945 0.3048)
			(stroke
				(width 0.1)
				(type default)
			)
			(layer "B.Fab")
		)
		(fp_line
			(start -0.120396 0.3048)
			(end -0.120396 0.2794)
			(stroke
				(width 0.1)
				(type default)
			)
			(layer "B.Fab")
		)
		(fp_line
			(start -0.67945 0.3048)
			(end -0.120396 0.3048)
			(stroke
				(width 0.1)
				(type default)
			)
			(layer "B.Fab")
		)
		(pad "1" smd circle
			(at 0.40005 0 270)
			(size 0 0)
			(layers "B.Cu" "B.Mask" "B.Paste")
			(net "VFG3P3_CLK_GEN")
		)
		(pad "2" smd circle
			(at -0.40005 0 270)
			(size 0 0)
			(layers "B.Cu" "B.Mask" "B.Paste")
			(net "GND")
		)
	)
	(footprint ""
		(layer "B.Cu")
		(at 189.001146 -321.554856 -90)
		(property "Reference" "C80"
			(at 0 0 90)
			(layer "B.SilkS")
			(hide yes)
			(effects
				(font
					(size 1.27 1.27)
				)
				(justify mirror)
			)
		)
		(property "Value" ""
			(at 0 0 90)
			(layer "B.Fab")
			(effects
				(font
					(size 1.27 1.27)
				)
				(justify mirror)
			)
		)
		(duplicate_pad_numbers_are_jumpers no)
		(fp_line
			(start -1.524 0.762)
			(end 1.524 0.762)
			(stroke
				(width 0.1524)
				(type default)
			)
			(layer "B.SilkS")
		)
		(fp_line
			(start 1.524 0.762)
			(end 1.524 -0.762)
			(stroke
				(width 0.1524)
				(type default)
			)
			(layer "B.SilkS")
		)
		(fp_line
			(start -1.524 -0.762)
			(end -1.524 0.762)
			(stroke
				(width 0.1524)
				(type default)
			)
			(layer "B.SilkS")
		)
		(fp_line
			(start 1.524 -0.762)
			(end -1.524 -0.762)
			(stroke
				(width 0.1524)
				(type default)
			)
			(layer "B.SilkS")
		)
		(fp_line
			(start -1.1049 0.724916)
			(end -1.1049 -0.724916)
			(stroke
				(width 0.1)
				(type default)
			)
			(layer "B.Fab")
		)
		(fp_line
			(start 1.1049 0.724916)
			(end -1.1049 0.724916)
			(stroke
				(width 0.1)
				(type default)
			)
			(layer "B.Fab")
		)
		(fp_line
			(start -1.1049 -0.724916)
			(end 1.1049 -0.724916)
			(stroke
				(width 0.1)
				(type default)
			)
			(layer "B.Fab")
		)
		(fp_line
			(start 1.1049 -0.724916)
			(end 1.1049 0.724916)
			(stroke
				(width 0.1)
				(type default)
			)
			(layer "B.Fab")
		)
		(pad "1" smd rect
			(at 0.889 0 270)
			(size 1.016 1.27)
			(layers "B.Cu" "B.Mask" "B.Paste")
			(net "P12V_S3_AUX_CPU1_NVDIMM")
		)
		(pad "2" smd rect
			(at -0.889 0 270)
			(size 1.016 1.27)
			(layers "B.Cu" "B.Mask" "B.Paste")
			(net "GND")
		)
	)
)
